# SCM (Grand Teton) — schematic netlist excerpt (pin names and nets, part order shuffled) for the footprints in the layout excerpt that follows; sources: Cadence DE-HDL packaged netlist, KiCad conversion of 12092022_DA0F0TMDCD0_F0T_Management_Board_D_brd_V3_OCP.brd

C75  Q_CAP  1UF 25V 10% X6S  pkg C0402  page 16 : A = A_BMC_ADCAV33 ; B = GND
C98  Q_CAP  0.1UF 25V 10% X7R  pkg 0402  page 16 : A = P1V2_AUX ; B = GND

(kicad_pcb
	(version 20260206)
	(generator "pcbnew")
	(generator_version "10.0")
	(general
		(thickness 1.6)
		(legacy_teardrops no)
	)
	(paper "A4")
	(title_block
		(title "12092022_DA0F0TMDCD0_F0T_Management_Board_D_brd_V3_OCP.brd")
		(comment 1 "Grand Teton / footprints 1147-1148 of 1440")
	)
	(layers
		(0 "F.Cu" signal "TOP")
		(4 "In1.Cu" signal "GND")
		(6 "In2.Cu" signal "IN1")
		(8 "In3.Cu" signal "GND1")
		(10 "In4.Cu" signal "IN2")
		(12 "In5.Cu" signal "VCC")
		(14 "In6.Cu" signal "VCC1")
		(16 "In7.Cu" signal "IN3")
		(18 "In8.Cu" signal "GND2")
		(20 "In9.Cu" signal "IN4")
		(22 "In10.Cu" signal "GND3")
		(2 "B.Cu" signal "BOTTOM")
		(9 "F.Adhes" user "F.Adhesive")
		(11 "B.Adhes" user "B.Adhesive")
		(13 "F.Paste" user "Package Geometry/Pastemask Top")
		(15 "B.Paste" user "Package Geometry/Pastemask Bottom")
		(5 "F.SilkS" user "Ref Des/Silkscreen Top")
		(7 "B.SilkS" user "Ref Des/Silkscreen Bottom")
		(1 "F.Mask" user "Board Geometry/Soldermask Top")
		(3 "B.Mask" user "Board Geometry/Soldermask Bottom")
		(17 "Dwgs.User" user "User.Drawings")
		(19 "Cmts.User" user "User.Comments")
		(21 "Eco1.User" user "User.Eco1")
		(23 "Eco2.User" user "User.Eco2")
		(25 "Edge.Cuts" user "Board Geometry/Outline")
		(27 "Margin" user)
		(31 "F.CrtYd" user "Package Geometry/Place Bound Top")
		(29 "B.CrtYd" user "Package Geometry/Place Bound Bottom")
		(35 "F.Fab" user "Ref Des/Assembly Top")
		(33 "B.Fab" user "Ref Des/Assembly Bottom")
	)
	(footprint ""
		(layer "B.Cu")
		(at 42.6974 -58.0136)
		(property "Reference" "C75"
			(at 0 0 0)
			(layer "B.SilkS")
			(hide yes)
			(effects
				(font
					(size 1.27 1.27)
				)
				(justify mirror)
			)
		)
		(property "Value" ""
			(at 0 0 0)
			(layer "B.Fab")
			(effects
				(font
					(size 1.27 1.27)
				)
				(justify mirror)
			)
		)
		(duplicate_pad_numbers_are_jumpers no)
		(fp_line
			(start -0.7874 -0.4064)
			(end -0.7874 0.4064)
			(stroke
				(width 0.1524)
				(type default)
			)
			(layer "B.SilkS")
		)
		(fp_line
			(start -0.7874 0.4064)
			(end 0.7874 0.4064)
			(stroke
				(width 0.1524)
				(type default)
			)
			(layer "B.SilkS")
		)
		(fp_line
			(start 0.7874 -0.4064)
			(end -0.7874 -0.4064)
			(stroke
				(width 0.1524)
				(type default)
			)
			(layer "B.SilkS")
		)
		(fp_line
			(start 0.7874 0.4064)
			(end 0.7874 -0.4064)
			(stroke
				(width 0.1524)
				(type default)
			)
			(layer "B.SilkS")
		)
		(fp_line
			(start -0.67945 -0.3048)
			(end -0.67945 0.3048)
			(stroke
				(width 0.1)
				(type default)
			)
			(layer "B.Fab")
		)
		(fp_line
			(start -0.67945 0.3048)
			(end -0.120396 0.3048)
			(stroke
				(width 0.1)
				(type default)
			)
			(layer "B.Fab")
		)
		(fp_line
			(start -0.12065 -0.3048)
			(end -0.67945 -0.3048)
			(stroke
				(width 0.1)
				(type default)
			)
			(layer "B.Fab")
		)
		(fp_line
			(start -0.12065 -0.2794)
			(end -0.12065 -0.3048)
			(stroke
				(width 0.1)
				(type default)
			)
			(layer "B.Fab")
		)
		(fp_line
			(start -0.120396 0.2794)
			(end 0.12065 0.2794)
			(stroke
				(width 0.1)
				(type default)
			)
			(layer "B.Fab")
		)
		(fp_line
			(start -0.120396 0.3048)
			(end -0.120396 0.2794)
			(stroke
				(width 0.1)
				(type default)
			)
			(layer "B.Fab")
		)
		(fp_line
			(start 0.12065 -0.305054)
			(end 0.12065 -0.2794)
			(stroke
				(width 0.1)
				(type default)
			)
			(layer "B.Fab")
		)
		(fp_line
			(start 0.12065 -0.2794)
			(end -0.12065 -0.2794)
			(stroke
				(width 0.1)
				(type default)
			)
			(layer "B.Fab")
		)
		(fp_line
			(start 0.12065 0.2794)
			(end 0.12065 0.3048)
			(stroke
				(width 0.1)
				(type default)
			)
			(layer "B.Fab")
		)
		(fp_line
			(start 0.12065 0.3048)
			(end 0.67945 0.3048)
			(stroke
				(width 0.1)
				(type default)
			)
			(layer "B.Fab")
		)
		(fp_line
			(start 0.67945 -0.305054)
			(end 0.12065 -0.305054)
			(stroke
				(width 0.1)
				(type default)
			)
			(layer "B.Fab")
		)
		(fp_line
			(start 0.67945 0.3048)
			(end 0.67945 -0.305054)
			(stroke
				(width 0.1)
				(type default)
			)
			(layer "B.Fab")
		)
		(pad "1" smd circle
			(at 0.40005 0 180)
			(size 0 0)
			(layers "B.Cu" "B.Mask" "B.Paste")
			(net "A_BMC_ADCAV33")
		)
		(pad "2" smd circle
			(at -0.40005 0 180)
			(size 0 0)
			(layers "B.Cu" "B.Mask" "B.Paste")
			(net "GND")
		)
	)
	(footprint ""
		(layer "B.Cu")
		(at 50.66411 -47.625 -90)
		(property "Reference" "C98"
			(at 0 0 90)
			(layer "B.SilkS")
			(hide yes)
			(effects
				(font
					(size 1.27 1.27)
				)
				(justify mirror)
			)
		)
		(property "Value" ""
			(at 0 0 90)
			(layer "B.Fab")
			(effects
				(font
					(size 1.27 1.27)
				)
				(justify mirror)
			)
		)
		(duplicate_pad_numbers_are_jumpers no)
		(fp_line
			(start -0.7874 0.4064)
			(end 0.7874 0.4064)
			(stroke
				(width 0.1524)
				(type default)
			)
			(layer "B.SilkS")
		)
		(fp_line
			(start 0.7874 0.4064)
			(end 0.7874 -0.4064)
			(stroke
				(width 0.1524)
				(type default)
			)
			(layer "B.SilkS")
		)
		(fp_line
			(start -0.7874 -0.4064)
			(end -0.7874 0.4064)
			(stroke
				(width 0.1524)
				(type default)
			)
			(layer "B.SilkS")
		)
		(fp_line
			(start 0.7874 -0.4064)
			(end -0.7874 -0.4064)
			(stroke
				(width 0.1524)
				(type default)
			)
			(layer "B.SilkS")
		)
		(fp_line
			(start -0.67945 0.3048)
			(end -0.120396 0.3048)
			(stroke
				(width 0.1)
				(type default)
			)
			(layer "B.Fab")
		)
		(fp_line
			(start -0.120396 0.3048)
			(end -0.120396 0.2794)
			(stroke
				(width 0.1)
				(type default)
			)
			(layer "B.Fab")
		)
		(fp_line
			(start 0.12065 0.3048)
			(end 0.67945 0.3048)
			(stroke
				(width 0.1)
				(type default)
			)
			(layer "B.Fab")
		)
		(fp_line
			(start 0.67945 0.3048)
			(end 0.67945 -0.305054)
			(stroke
				(width 0.1)
				(type default)
			)
			(layer "B.Fab")
		)
		(fp_line
			(start -0.120396 0.2794)
			(end 0.12065 0.2794)
			(stroke
				(width 0.1)
				(type default)
			)
			(layer "B.Fab")
		)
		(fp_line
			(start 0.12065 0.2794)
			(end 0.12065 0.3048)
			(stroke
				(width 0.1)
				(type default)
			)
			(layer "B.Fab")
		)
		(fp_line
			(start -0.12065 -0.2794)
			(end -0.12065 -0.3048)
			(stroke
				(width 0.1)
				(type default)
			)
			(layer "B.Fab")
		)
		(fp_line
			(start 0.12065 -0.2794)
			(end -0.12065 -0.2794)
			(stroke
				(width 0.1)
				(type default)
			)
			(layer "B.Fab")
		)
		(fp_line
			(start -0.67945 -0.3048)
			(end -0.67945 0.3048)
			(stroke
				(width 0.1)
				(type default)
			)
			(layer "B.Fab")
		)
		(fp_line
			(start -0.12065 -0.3048)
			(end -0.67945 -0.3048)
			(stroke
				(width 0.1)
				(type default)
			)
			(layer "B.Fab")
		)
		(fp_line
			(start 0.12065 -0.305054)
			(end 0.12065 -0.2794)
			(stroke
				(width 0.1)
				(type default)
			)
			(layer "B.Fab")
		)
		(fp_line
			(start 0.67945 -0.305054)
			(end 0.12065 -0.305054)
			(stroke
				(width 0.1)
				(type default)
			)
			(layer "B.Fab")
		)
		(pad "1" smd circle
			(at 0.40005 0 90)
			(size 0 0)
			(layers "B.Cu" "B.Mask" "B.Paste")
			(net "P1V2_AUX")
		)
		(pad "2" smd circle
			(at -0.40005 0 90)
			(size 0 0)
			(layers "B.Cu" "B.Mask" "B.Paste")
			(net "GND")
		)
	)
)
